(kicad_pcb
	(version 20260206)
	(generator "pcbnew")
	(generator_version "10.0")
	(general
		(thickness 1.6)
		(legacy_teardrops no)
	)
	(paper "A4")
	(title_block
		(title "9054_F0T_PDB_BD_GPU_F_V04_1213_1550_OCP.brd")
		(comment 1 "Grand Teton / footprints 533-535 of 608")
	)
	(layers
		(0 "F.Cu" signal "TOP")
		(4 "In1.Cu" signal "GND")
		(6 "In2.Cu" signal "IN1")
		(8 "In3.Cu" signal "GND1")
		(10 "In4.Cu" signal "VCC")
		(12 "In5.Cu" signal "VCC1")
		(14 "In6.Cu" signal "GND2")
		(16 "In7.Cu" signal "IN2")
		(18 "In8.Cu" signal "GND3")
		(2 "B.Cu" signal "BOTTOM")
		(9 "F.Adhes" user "F.Adhesive")
		(11 "B.Adhes" user "B.Adhesive")
		(13 "F.Paste" user "Package Geometry/Pastemask Top")
		(15 "B.Paste" user "Package Geometry/Pastemask Bottom")
		(5 "F.SilkS" user "Ref Des/Silkscreen Top")
		(7 "B.SilkS" user "Ref Des/Silkscreen Bottom")
		(1 "F.Mask" user "Board Geometry/Soldermask Top")
		(3 "B.Mask" user "Board Geometry/Soldermask Bottom")
		(17 "Dwgs.User" user "User.Drawings")
		(19 "Cmts.User" user "User.Comments")
		(21 "Eco1.User" user "User.Eco1")
		(23 "Eco2.User" user "User.Eco2")
		(25 "Edge.Cuts" user "Board Geometry/Outline")
		(27 "Margin" user)
		(31 "F.CrtYd" user "Package Geometry/Place Bound Top")
		(29 "B.CrtYd" user "Package Geometry/Place Bound Bottom")
		(35 "F.Fab" user "Ref Des/Assembly Top")
		(33 "B.Fab" user "Ref Des/Assembly Bottom")
	)
	(footprint ""
		(layer "B.Cu")
		(at 154.097736 -70.104 180)
		(property "Reference" "PU8"
			(at -3.636264 -4.59867 0)
			(unlocked yes)
			(layer "B.SilkS")
			(effects
				(font
					(size 0.7874 0.5842)
					(thickness 0.1524)
				)
				(justify left mirror)
			)
		)
		(property "Value" ""
			(at 0 0 0)
			(layer "B.Fab")
			(effects
				(font
					(size 1.27 1.27)
				)
				(justify mirror)
			)
		)
		(duplicate_pad_numbers_are_jumpers no)
		(fp_line
			(start 3.549904 3.549904)
			(end 3.549904 3.0226)
			(stroke
				(width 0.1524)
				(type default)
			)
			(layer "B.SilkS")
		)
		(fp_line
			(start 3.549904 -0.0254)
			(end 3.549904 -1.4732)
			(stroke
				(width 0.1524)
				(type default)
			)
			(layer "B.SilkS")
		)
		(fp_line
			(start 3.549904 -3.0226)
			(end 3.549904 -3.549904)
			(stroke
				(width 0.1524)
				(type default)
			)
			(layer "B.SilkS")
		)
		(fp_line
			(start 3.549904 -3.549904)
			(end 3.0226 -3.549904)
			(stroke
				(width 0.1524)
				(type default)
			)
			(layer "B.SilkS")
		)
		(fp_line
			(start 3.0226 3.549904)
			(end 3.549904 3.549904)
			(stroke
				(width 0.1524)
				(type default)
			)
			(layer "B.SilkS")
		)
		(fp_line
			(start 2.4638 -3.549904)
			(end 1.03124 -3.549904)
			(stroke
				(width 0.1524)
				(type default)
			)
			(layer "B.SilkS")
		)
		(fp_line
			(start 1.03124 3.549904)
			(end 2.4638 3.549904)
			(stroke
				(width 0.1524)
				(type default)
			)
			(layer "B.SilkS")
		)
		(fp_line
			(start -3.0226 -3.549904)
			(end -3.549904 -3.549904)
			(stroke
				(width 0.1524)
				(type default)
			)
			(layer "B.SilkS")
		)
		(fp_line
			(start -3.549904 3.549904)
			(end -3.0226 3.549904)
			(stroke
				(width 0.1524)
				(type default)
			)
			(layer "B.SilkS")
		)
		(fp_line
			(start -3.549904 3.0226)
			(end -3.549904 3.549904)
			(stroke
				(width 0.1524)
				(type default)
			)
			(layer "B.SilkS")
		)
		(fp_line
			(start -3.549904 -3.549904)
			(end -3.549904 -3.0226)
			(stroke
				(width 0.1524)
				(type default)
			)
			(layer "B.SilkS")
		)
		(fp_poly
			(pts
				(xy 4.134104 -3.041904) (xy 3.549904 -3.041904) (xy 3.549904 -3.626104) (xy 4.134104 -3.626104)
			)
			(stroke
				(width 0)
				(type default)
			)
			(fill yes)
			(layer "B.SilkS")
		)
		(fp_line
			(start 3.549904 3.549904)
			(end 3.549904 -3.549904)
			(stroke
				(width 0.1)
				(type default)
			)
			(layer "B.Fab")
		)
		(fp_line
			(start 3.549904 -3.549904)
			(end -3.549904 -3.549904)
			(stroke
				(width 0.1)
				(type default)
			)
			(layer "B.Fab")
		)
		(fp_line
			(start -3.549904 3.549904)
			(end 3.549904 3.549904)
			(stroke
				(width 0.1)
				(type default)
			)
			(layer "B.Fab")
		)
		(fp_line
			(start -3.549904 -3.549904)
			(end -3.549904 3.549904)
			(stroke
				(width 0.1)
				(type default)
			)
			(layer "B.Fab")
		)
		(fp_poly
			(pts
				(xy 4.134104 -3.041904) (xy 3.549904 -3.041904) (xy 3.549904 -3.626104) (xy 4.134104 -3.626104)
			)
			(stroke
				(width 0)
				(type default)
			)
			(fill yes)
			(layer "B.Fab")
		)
		(pad "1" smd rect
			(at 3.425444 -2.750058 90)
			(size 0.2794 0.7112)
			(layers "B.Cu" "B.Mask" "B.Paste")
			(net "P52V_HS2")
		)
		(pad "2" smd rect
			(at 3.400044 -2.249932 90)
			(size 0.2794 0.762)
			(layers "B.Cu" "B.Mask" "B.Paste")
			(net "P52V_HS2_4287_GATE2_R")
		)
		(pad "3" smd rect
			(at 3.400044 -1.75006 90)
			(size 0.2794 0.762)
			(layers "B.Cu" "B.Mask" "B.Paste")
			(net "P52V_HS2_4287_GATE_R")
		)
		(pad "4" smd rect
			(at 3.400044 0.249936 90)
			(size 0.2794 0.762)
			(layers "B.Cu" "B.Mask" "B.Paste")
			(net "P52V_HS2_4287_ADC_N")
		)
		(pad "5" smd rect
			(at 3.400044 0.750062 90)
			(size 0.2794 0.762)
			(layers "B.Cu" "B.Mask" "B.Paste")
			(net "P52V_HS2_4287_S1N")
		)
		(pad "6" smd rect
			(at 3.400044 1.249934 90)
			(size 0.2794 0.762)
			(layers "B.Cu" "B.Mask" "B.Paste")
			(net "P52V_HS2_4287_S1P")
		)
		(pad "7" smd rect
			(at 3.400044 1.75006 90)
			(size 0.2794 0.762)
			(layers "B.Cu" "B.Mask" "B.Paste")
			(net "P52V_HS2_4287_ADC_P")
		)
		(pad "8" smd rect
			(at 3.400044 2.249932 90)
			(size 0.2794 0.762)
			(layers "B.Cu" "B.Mask" "B.Paste")
			(net "P52V_HS2_4287_S2N")
		)
		(pad "9" smd rect
			(at 3.425444 2.750058 90)
			(size 0.2794 0.7112)
			(layers "B.Cu" "B.Mask" "B.Paste")
			(net "P52V_HS2_4287_S2P")
		)
		(pad "10" smd rect
			(at 2.750058 3.425444)
			(size 0.2794 0.7112)
			(layers "B.Cu" "B.Mask" "B.Paste")
			(net "P52V_2")
		)
		(pad "11" smd rect
			(at 0.750062 3.400044)
			(size 0.2794 0.762)
			(layers "B.Cu" "B.Mask" "B.Paste")
			(net "P52V_HS2_UVLO_EN")
		)
		(pad "12" smd rect
			(at 0.249936 3.400044)
			(size 0.2794 0.762)
			(layers "B.Cu" "B.Mask" "B.Paste")
			(net "P52V_HS2_OV")
		)
		(pad "13" smd rect
			(at -0.249936 3.400044)
			(size 0.2794 0.762)
			(layers "B.Cu" "B.Mask" "B.Paste")
			(net "P52V_HS2_INTVCC")
		)
		(pad "14" smd rect
			(at -0.750062 3.400044)
			(size 0.2794 0.762)
			(layers "B.Cu" "B.Mask" "B.Paste")
			(net "GND1_FIELD_SIGNAL")
		)
		(pad "15" smd rect
			(at -1.249934 3.400044)
			(size 0.2794 0.762)
			(layers "B.Cu" "B.Mask" "B.Paste")
			(net "P52V_HS2_DVCC")
		)
		(pad "16" smd rect
			(at -1.75006 3.400044)
			(size 0.2794 0.762)
			(layers "B.Cu" "B.Mask" "B.Paste")
			(net "P52V_HS2_ADR0")
		)
		(pad "17" smd rect
			(at -2.249932 3.400044)
			(size 0.2794 0.762)
			(layers "B.Cu" "B.Mask" "B.Paste")
			(net "P52V_HS2_ADR1")
		)
		(pad "18" smd rect
			(at -2.750058 3.425444)
			(size 0.2794 0.7112)
			(layers "B.Cu" "B.Mask" "B.Paste")
			(net "Net_410")
		)
		(pad "19" smd rect
			(at -3.425444 2.750058 90)
			(size 0.2794 0.7112)
			(layers "B.Cu" "B.Mask" "B.Paste")
			(net "P52V_HS2_MODE")
		)
		(pad "20" smd rect
			(at -3.400044 2.249932 90)
			(size 0.2794 0.762)
			(layers "B.Cu" "B.Mask" "B.Paste")
			(net "P52V_HS2_TMR")
		)
		(pad "21" smd rect
			(at -3.400044 1.75006 90)
			(size 0.2794 0.762)
			(layers "B.Cu" "B.Mask" "B.Paste")
			(net "P52V_HS2_CLKIN")
		)
		(pad "22" smd rect
			(at -3.400044 1.249934 90)
			(size 0.2794 0.762)
			(layers "B.Cu" "B.Mask" "B.Paste")
			(net "Net_414")
		)
		(pad "23" smd rect
			(at -3.400044 0.750062 90)
			(size 0.2794 0.762)
			(layers "B.Cu" "B.Mask" "B.Paste")
			(net "P52V_HS2_EN")
		)
		(pad "24" smd rect
			(at -3.400044 0.249936 90)
			(size 0.2794 0.762)
			(layers "B.Cu" "B.Mask" "B.Paste")
			(net "P52V_HS2_SIO")
		)
		(pad "25" smd rect
			(at -3.400044 -0.249936 90)
			(size 0.2794 0.762)
			(layers "B.Cu" "B.Mask" "B.Paste")
			(net "P52V_HS2_SCK")
		)
		(pad "26" smd rect
			(at -3.400044 -0.750062 90)
			(size 0.2794 0.762)
			(layers "B.Cu" "B.Mask" "B.Paste")
			(net "P52V_HS2_CS")
		)
		(pad "27" smd rect
			(at -3.400044 -1.249934 90)
			(size 0.2794 0.762)
			(layers "B.Cu" "B.Mask" "B.Paste")
			(net "SMB_P52V_PDB_SCL_R4")
		)
		(pad "28" smd rect
			(at -3.400044 -1.75006 90)
			(size 0.2794 0.762)
			(layers "B.Cu" "B.Mask" "B.Paste")
			(net "SMB_P52V_HS2_SDAI")
		)
		(pad "29" smd rect
			(at -3.400044 -2.249932 90)
			(size 0.2794 0.762)
			(layers "B.Cu" "B.Mask" "B.Paste")
			(net "SMB_P52V_HS2_SDAO")
		)
		(pad "30" smd rect
			(at -3.425444 -2.750058 90)
			(size 0.2794 0.7112)
			(layers "B.Cu" "B.Mask" "B.Paste")
			(net "Net_411")
		)
		(pad "31" smd rect
			(at -2.750058 -3.425444)
			(size 0.2794 0.7112)
			(layers "B.Cu" "B.Mask" "B.Paste")
			(net "Net_412")
		)
		(pad "32" smd rect
			(at -2.249932 -3.400044)
			(size 0.2794 0.762)
			(layers "B.Cu" "B.Mask" "B.Paste")
			(net "Net_413")
		)
		(pad "33" smd rect
			(at -1.75006 -3.400044)
			(size 0.2794 0.762)
			(layers "B.Cu" "B.Mask" "B.Paste")
			(net "GND1_FIELD_SIGNAL")
		)
		(pad "34" smd rect
			(at -1.249934 -3.400044)
			(size 0.2794 0.762)
			(layers "B.Cu" "B.Mask" "B.Paste")
			(net "GND1_FIELD_SIGNAL")
		)
		(pad "35" smd rect
			(at -0.750062 -3.400044)
			(size 0.2794 0.762)
			(layers "B.Cu" "B.Mask" "B.Paste")
			(net "P52V_HS2_TEMP")
		)
		(pad "36" smd rect
			(at -0.249936 -3.400044)
			(size 0.2794 0.762)
			(layers "B.Cu" "B.Mask" "B.Paste")
			(net "P52V_HS2_FLT")
		)
		(pad "37" smd rect
			(at 0.249936 -3.400044)
			(size 0.2794 0.762)
			(layers "B.Cu" "B.Mask" "B.Paste")
			(net "PWRGD_P52V_HS2_4287_PG_N")
		)
		(pad "38" smd rect
			(at 0.750062 -3.400044)
			(size 0.2794 0.762)
			(layers "B.Cu" "B.Mask" "B.Paste")
			(net "P52V_HS2_FB")
		)
		(pad "39" smd rect
			(at 2.750058 -3.425444)
			(size 0.2794 0.7112)
			(layers "B.Cu" "B.Mask" "B.Paste")
			(net "P52V_HS2_VDSFB")
		)
		(pad "40" smd circle
			(at -0.87503 0)
			(size 0 0)
			(layers "B.Cu" "B.Mask" "B.Paste")
			(net "GND1_FIELD_SIGNAL")
		)
		(zone
			(layer "B.Cu")
			(hatch none 0.5)
			(connect_pads
				(clearance 0)
			)
			(min_thickness 0.25)
			(keepout
				(tracks not_allowed)
				(vias allowed)
				(pads allowed)
				(copperpour not_allowed)
				(footprints allowed)
			)
			(placement
				(enabled no)
				(sheetname "")
			)
			(fill
				(thermal_gap 0.5)
				(thermal_bridge_width 0.5)
				(island_removal_mode 0)
			)
			(polygon
				(pts
					(xy 151.129492 -67.66052) (xy 151.129492 -69.4436) (xy 153.081736 -69.4436) (xy 153.081736 -67.7164)
					(xy 153.462736 -67.3354) (xy 156.866336 -67.3354) (xy 156.866336 -72.8726) (xy 153.081736 -72.8726)
					(xy 153.081736 -69.469) (xy 151.129492 -69.469) (xy 151.129492 -72.55002) (xy 151.078692 -72.55002)
					(xy 151.078692 -73.123044) (xy 153.150316 -73.123044) (xy 153.150316 -73.072244) (xy 156.543756 -73.072244)
					(xy 156.543756 -73.123044) (xy 157.11678 -73.123044) (xy 157.11678 -72.55002) (xy 157.06598 -72.55002)
					(xy 157.06598 -67.65798) (xy 157.11678 -67.65798) (xy 157.11678 -67.084956) (xy 156.543756 -67.084956)
					(xy 156.543756 -67.135756) (xy 153.150316 -67.135756) (xy 153.150316 -67.084956) (xy 151.078692 -67.084956)
					(xy 151.078692 -67.66052)
				)
			)
		)
	)
	(footprint ""
		(layer "B.Cu")
		(at 284.7594 -64.516)
		(property "Reference" "PC551"
			(at 0 0 0)
			(layer "B.SilkS")
			(hide yes)
			(effects
				(font
					(size 1.27 1.27)
				)
				(justify mirror)
			)
		)
		(property "Value" ""
			(at 0 0 0)
			(layer "B.Fab")
			(effects
				(font
					(size 1.27 1.27)
				)
				(justify mirror)
			)
		)
		(duplicate_pad_numbers_are_jumpers no)
		(fp_line
			(start -0.7874 -0.4064)
			(end -0.7874 0.4064)
			(stroke
				(width 0.1524)
				(type default)
			)
			(layer "B.SilkS")
		)
		(fp_line
			(start -0.7874 0.4064)
			(end 0.7874 0.4064)
			(stroke
				(width 0.1524)
				(type default)
			)
			(layer "B.SilkS")
		)
		(fp_line
			(start 0.7874 -0.4064)
			(end -0.7874 -0.4064)
			(stroke
				(width 0.1524)
				(type default)
			)
			(layer "B.SilkS")
		)
		(fp_line
			(start 0.7874 0.4064)
			(end 0.7874 -0.4064)
			(stroke
				(width 0.1524)
				(type default)
			)
			(layer "B.SilkS")
		)
		(fp_line
			(start -0.67945 -0.3048)
			(end -0.67945 0.3048)
			(stroke
				(width 0.1)
				(type default)
			)
			(layer "B.Fab")
		)
		(fp_line
			(start -0.67945 0.3048)
			(end -0.120396 0.3048)
			(stroke
				(width 0.1)
				(type default)
			)
			(layer "B.Fab")
		)
		(fp_line
			(start -0.12065 -0.3048)
			(end -0.67945 -0.3048)
			(stroke
				(width 0.1)
				(type default)
			)
			(layer "B.Fab")
		)
		(fp_line
			(start -0.12065 -0.2794)
			(end -0.12065 -0.3048)
			(stroke
				(width 0.1)
				(type default)
			)
			(layer "B.Fab")
		)
		(fp_line
			(start -0.120396 0.2794)
			(end 0.12065 0.2794)
			(stroke
				(width 0.1)
				(type default)
			)
			(layer "B.Fab")
		)
		(fp_line
			(start -0.120396 0.3048)
			(end -0.120396 0.2794)
			(stroke
				(width 0.1)
				(type default)
			)
			(layer "B.Fab")
		)
		(fp_line
			(start 0.12065 -0.305054)
			(end 0.12065 -0.2794)
			(stroke
				(width 0.1)
				(type default)
			)
			(layer "B.Fab")
		)
		(fp_line
			(start 0.12065 -0.2794)
			(end -0.12065 -0.2794)
			(stroke
				(width 0.1)
				(type default)
			)
			(layer "B.Fab")
		)
		(fp_line
			(start 0.12065 0.2794)
			(end 0.12065 0.3048)
			(stroke
				(width 0.1)
				(type default)
			)
			(layer "B.Fab")
		)
		(fp_line
			(start 0.12065 0.3048)
			(end 0.67945 0.3048)
			(stroke
				(width 0.1)
				(type default)
			)
			(layer "B.Fab")
		)
		(fp_line
			(start 0.67945 -0.305054)
			(end 0.12065 -0.305054)
			(stroke
				(width 0.1)
				(type default)
			)
			(layer "B.Fab")
		)
		(fp_line
			(start 0.67945 0.3048)
			(end 0.67945 -0.305054)
			(stroke
				(width 0.1)
				(type default)
			)
			(layer "B.Fab")
		)
		(pad "1" smd circle
			(at 0.40005 0 180)
			(size 0 0)
			(layers "B.Cu" "B.Mask" "B.Paste")
			(net "HS1_TMR1")
		)
		(pad "2" smd circle
			(at -0.40005 0 180)
			(size 0 0)
			(layers "B.Cu" "B.Mask" "B.Paste")
			(net "GND_FIELD_SIGNAL")
		)
	)
	(footprint ""
		(layer "B.Cu")
		(at 341.503 -47.244 90)
		(property "Reference" "PC82"
			(at 0 0 90)
			(layer "B.SilkS")
			(hide yes)
			(effects
				(font
					(size 1.27 1.27)
				)
				(justify mirror)
			)
		)
		(property "Value" ""
			(at 0 0 90)
			(layer "B.Fab")
			(effects
				(font
					(size 1.27 1.27)
				)
				(justify mirror)
			)
		)
		(duplicate_pad_numbers_are_jumpers no)
		(fp_line
			(start 1.2954 -0.5842)
			(end -1.2954 -0.5842)
			(stroke
				(width 0.1524)
				(type default)
			)
			(layer "B.SilkS")
		)
		(fp_line
			(start -1.2954 -0.5842)
			(end -1.2954 0.5842)
			(stroke
				(width 0.1524)
				(type default)
			)
			(layer "B.SilkS")
		)
		(fp_line
			(start 1.2954 0.5842)
			(end 1.2954 -0.5842)
			(stroke
				(width 0.1524)
				(type default)
			)
			(layer "B.SilkS")
		)
		(fp_line
			(start -1.2954 0.5842)
			(end 1.2954 0.5842)
			(stroke
				(width 0.1524)
				(type default)
			)
			(layer "B.SilkS")
		)
		(fp_line
			(start 0.8636 -0.4572)
			(end -0.8636 -0.4572)
			(stroke
				(width 0.1)
				(type default)
			)
			(layer "B.Fab")
		)
		(fp_line
			(start -0.8636 -0.4572)
			(end -0.8636 -0.4064)
			(stroke
				(width 0.1)
				(type default)
			)
			(layer "B.Fab")
		)
		(fp_line
			(start 1.1938 -0.4064)
			(end 0.8636 -0.4064)
			(stroke
				(width 0.1)
				(type default)
			)
			(layer "B.Fab")
		)
		(fp_line
			(start 0.8636 -0.4064)
			(end 0.8636 -0.4572)
			(stroke
				(width 0.1)
				(type default)
			)
			(layer "B.Fab")
		)
		(fp_line
			(start -0.8636 -0.4064)
			(end -1.1938 -0.4064)
			(stroke
				(width 0.1)
				(type default)
			)
			(layer "B.Fab")
		)
		(fp_line
			(start -1.1938 -0.4064)
			(end -1.1938 0.4064)
			(stroke
				(width 0.1)
				(type default)
			)
			(layer "B.Fab")
		)
		(fp_line
			(start 1.1938 0.4064)
			(end 1.1938 -0.4064)
			(stroke
				(width 0.1)
				(type default)
			)
			(layer "B.Fab")
		)
		(fp_line
			(start 0.8636 0.4064)
			(end 1.1938 0.4064)
			(stroke
				(width 0.1)
				(type default)
			)
			(layer "B.Fab")
		)
		(fp_line
			(start -0.8636 0.4064)
			(end -0.8636 0.4572)
			(stroke
				(width 0.1)
				(type default)
			)
			(layer "B.Fab")
		)
		(fp_line
			(start -1.1938 0.4064)
			(end -0.8636 0.4064)
			(stroke
				(width 0.1)
				(type default)
			)
			(layer "B.Fab")
		)
		(fp_line
			(start 0.8636 0.4572)
			(end 0.8636 0.4064)
			(stroke
				(width 0.1)
				(type default)
			)
			(layer "B.Fab")
		)
		(fp_line
			(start -0.8636 0.4572)
			(end 0.8636 0.4572)
			(stroke
				(width 0.1)
				(type default)
			)
			(layer "B.Fab")
		)
		(pad "1" smd rect
			(at 0.7366 0)
			(size 0.7112 0.8128)
			(layers "B.Cu" "B.Mask" "B.Paste")
			(net "P52V_HS1_4287_GATE_R")
		)
		(pad "2" smd rect
			(at -0.7366 0)
			(size 0.7112 0.8128)
			(layers "B.Cu" "B.Mask" "B.Paste")
			(net "P52V_HS1")
		)
	)
)
